(kicad_pcb
	(version 20260206)
	(generator "pcbnew")
	(generator_version "10.0")
	(general
		(thickness 1.6)
		(legacy_teardrops no)
	)
	(paper "A4")
	(title_block
		(title "04192023_DAF0TMB3IC0_F0TG_MB_C_brd_V02_OCP.brd")
		(comment 1 "Grand Teton / footprints 747-752 of 8354")
	)
	(layers
		(0 "F.Cu" signal "TOP")
		(4 "In1.Cu" signal "GND")
		(6 "In2.Cu" signal "IN1")
		(8 "In3.Cu" signal "GND1")
		(10 "In4.Cu" signal "IN2")
		(12 "In5.Cu" signal "GND2")
		(14 "In6.Cu" signal "IN3")
		(16 "In7.Cu" signal "GND3")
		(18 "In8.Cu" signal "VCC")
		(20 "In9.Cu" signal "VCC1")
		(22 "In10.Cu" signal "GND4")
		(24 "In11.Cu" signal "IN4")
		(26 "In12.Cu" signal "GND5")
		(28 "In13.Cu" signal "IN5")
		(30 "In14.Cu" signal "GND6")
		(32 "In15.Cu" signal "IN6")
		(34 "In16.Cu" signal "GND7")
		(2 "B.Cu" signal "BOTTOM")
		(9 "F.Adhes" user "F.Adhesive")
		(11 "B.Adhes" user "B.Adhesive")
		(13 "F.Paste" user "Package Geometry/Pastemask Top")
		(15 "B.Paste" user "Package Geometry/Pastemask Bottom")
		(5 "F.SilkS" user "Ref Des/Silkscreen Top")
		(7 "B.SilkS" user "Ref Des/Silkscreen Bottom")
		(1 "F.Mask" user "Board Geometry/Soldermask Top")
		(3 "B.Mask" user "Board Geometry/Soldermask Bottom")
		(17 "Dwgs.User" user "User.Drawings")
		(19 "Cmts.User" user "User.Comments")
		(21 "Eco1.User" user "User.Eco1")
		(23 "Eco2.User" user "User.Eco2")
		(25 "Edge.Cuts" user "Board Geometry/Outline")
		(27 "Margin" user)
		(31 "F.CrtYd" user "Package Geometry/Place Bound Top")
		(29 "B.CrtYd" user "Package Geometry/Place Bound Bottom")
		(35 "F.Fab" user "Ref Des/Assembly Top")
		(33 "B.Fab" user "Ref Des/Assembly Bottom")
	)
	(footprint ""
		(layer "F.Cu")
		(at 38.78707 -171.980606 180)
		(property "Reference" "U107"
			(at -2.3368 -2.662682 0)
			(unlocked yes)
			(layer "F.SilkS")
			(effects
				(font
					(size 0.7874 0.5842)
					(thickness 0.1524)
				)
			)
		)
		(property "Value" ""
			(at 0 0 180)
			(layer "F.Fab")
			(effects
				(font
					(size 1.27 1.27)
				)
			)
		)
		(duplicate_pad_numbers_are_jumpers no)
		(fp_line
			(start 1.03378 1.284478)
			(end -1.03378 1.284478)
			(stroke
				(width 0.1524)
				(type default)
			)
			(layer "F.SilkS")
		)
		(fp_line
			(start 1.03378 -1.284478)
			(end 1.03378 1.284478)
			(stroke
				(width 0.1524)
				(type default)
			)
			(layer "F.SilkS")
		)
		(fp_line
			(start -1.03378 1.284478)
			(end -1.03378 -1.284478)
			(stroke
				(width 0.1524)
				(type default)
			)
			(layer "F.SilkS")
		)
		(fp_line
			(start -1.03378 -1.284478)
			(end 1.03378 -1.284478)
			(stroke
				(width 0.1524)
				(type default)
			)
			(layer "F.SilkS")
		)
		(fp_poly
			(pts
				(xy -1.663192 -1.558798) (xy -1.327658 -0.971296) (xy -1.99898 -1.05537)
			)
			(stroke
				(width 0)
				(type default)
			)
			(fill yes)
			(layer "F.SilkS")
		)
		(fp_line
			(start 0.774954 1.02489)
			(end -0.774954 1.02489)
			(stroke
				(width 0.1)
				(type default)
			)
			(layer "F.Fab")
		)
		(fp_line
			(start 0.774954 -1.02489)
			(end 0.774954 1.02489)
			(stroke
				(width 0.1)
				(type default)
			)
			(layer "F.Fab")
		)
		(fp_line
			(start -0.774954 1.02489)
			(end -0.774954 -1.02489)
			(stroke
				(width 0.1)
				(type default)
			)
			(layer "F.Fab")
		)
		(fp_line
			(start -0.774954 -1.02489)
			(end 0.774954 -1.02489)
			(stroke
				(width 0.1)
				(type default)
			)
			(layer "F.Fab")
		)
		(fp_poly
			(pts
				(xy -1.201674 -0.750062) (xy -1.806702 -0.447548) (xy -1.806702 -1.052576)
			)
			(stroke
				(width 0)
				(type default)
			)
			(fill yes)
			(layer "F.Fab")
		)
		(pad "1" smd rect
			(at -0.64008 -0.750062 270)
			(size 0.3048 0.5334)
			(layers "F.Cu" "F.Mask" "F.Paste")
			(net "I3C_0_SPD_DDRAF_CPU1_SCL")
		)
		(pad "2" smd rect
			(at -0.64008 -0.249936 270)
			(size 0.254 0.5334)
			(layers "F.Cu" "F.Mask" "F.Paste")
			(net "I3C_0_SPD_DDRAF_CPU1_SDA")
		)
		(pad "3" smd rect
			(at -0.64008 0.249936 270)
			(size 0.254 0.5334)
			(layers "F.Cu" "F.Mask" "F.Paste")
			(net "I3C_SCM_2_R_SCL")
		)
		(pad "4" smd rect
			(at -0.64008 0.750062 270)
			(size 0.3048 0.5334)
			(layers "F.Cu" "F.Mask" "F.Paste")
			(net "I3C_SCM_2_R_SDA")
		)
		(pad "5" smd rect
			(at 0 0.839978 180)
			(size 0.3302 0.635)
			(layers "F.Cu" "F.Mask" "F.Paste")
			(net "GND")
		)
		(pad "6" smd rect
			(at 0.64008 0.750062 270)
			(size 0.3048 0.5334)
			(layers "F.Cu" "F.Mask" "F.Paste")
			(net "FM_I3C_CPU1_MUX0_OE_N")
		)
		(pad "7" smd rect
			(at 0.64008 0.249936 270)
			(size 0.254 0.5334)
			(layers "F.Cu" "F.Mask" "F.Paste")
			(net "I3C_SPD_DDRAF_CPU1_LVC1_SDA")
		)
		(pad "8" smd rect
			(at 0.64008 -0.249936 270)
			(size 0.254 0.5334)
			(layers "F.Cu" "F.Mask" "F.Paste")
			(net "I3C_SPD_DDRAF_CPU1_LVC1_SCL")
		)
		(pad "9" smd rect
			(at 0.64008 -0.750062 270)
			(size 0.3048 0.5334)
			(layers "F.Cu" "F.Mask" "F.Paste")
			(net "FM_I3C_CPU1_MUX0_SEL")
		)
		(pad "10" smd rect
			(at 0 -0.839978 180)
			(size 0.3302 0.635)
			(layers "F.Cu" "F.Mask" "F.Paste")
			(net "P3V3_AUX")
		)
	)
	(footprint ""
		(layer "F.Cu")
		(at 326.662288 -392.48588 180)
		(property "Reference" "R960"
			(at 0 0 180)
			(layer "F.SilkS")
			(hide yes)
			(effects
				(font
					(size 1.27 1.27)
				)
			)
		)
		(property "Value" ""
			(at 0 0 180)
			(layer "F.Fab")
			(effects
				(font
					(size 1.27 1.27)
				)
			)
		)
		(duplicate_pad_numbers_are_jumpers no)
		(fp_line
			(start 0.7874 0.4064)
			(end -0.7874 0.4064)
			(stroke
				(width 0.1524)
				(type default)
			)
			(layer "F.SilkS")
		)
		(fp_line
			(start 0.7874 -0.4064)
			(end 0.7874 0.4064)
			(stroke
				(width 0.1524)
				(type default)
			)
			(layer "F.SilkS")
		)
		(fp_line
			(start -0.7874 0.4064)
			(end -0.7874 -0.4064)
			(stroke
				(width 0.1524)
				(type default)
			)
			(layer "F.SilkS")
		)
		(fp_line
			(start -0.7874 -0.4064)
			(end 0.7874 -0.4064)
			(stroke
				(width 0.1524)
				(type default)
			)
			(layer "F.SilkS")
		)
		(fp_line
			(start 0.67945 0.3048)
			(end 0.120396 0.3048)
			(stroke
				(width 0.1)
				(type default)
			)
			(layer "F.Fab")
		)
		(fp_line
			(start 0.67945 -0.3048)
			(end 0.67945 0.3048)
			(stroke
				(width 0.1)
				(type default)
			)
			(layer "F.Fab")
		)
		(fp_line
			(start 0.12065 -0.2794)
			(end 0.12065 -0.3048)
			(stroke
				(width 0.1)
				(type default)
			)
			(layer "F.Fab")
		)
		(fp_line
			(start 0.12065 -0.3048)
			(end 0.67945 -0.3048)
			(stroke
				(width 0.1)
				(type default)
			)
			(layer "F.Fab")
		)
		(fp_line
			(start 0.120396 0.3048)
			(end 0.120396 0.2794)
			(stroke
				(width 0.1)
				(type default)
			)
			(layer "F.Fab")
		)
		(fp_line
			(start 0.120396 0.2794)
			(end -0.12065 0.2794)
			(stroke
				(width 0.1)
				(type default)
			)
			(layer "F.Fab")
		)
		(fp_line
			(start -0.12065 0.3048)
			(end -0.67945 0.3048)
			(stroke
				(width 0.1)
				(type default)
			)
			(layer "F.Fab")
		)
		(fp_line
			(start -0.12065 0.2794)
			(end -0.12065 0.3048)
			(stroke
				(width 0.1)
				(type default)
			)
			(layer "F.Fab")
		)
		(fp_line
			(start -0.12065 -0.2794)
			(end 0.12065 -0.2794)
			(stroke
				(width 0.1)
				(type default)
			)
			(layer "F.Fab")
		)
		(fp_line
			(start -0.12065 -0.305054)
			(end -0.12065 -0.2794)
			(stroke
				(width 0.1)
				(type default)
			)
			(layer "F.Fab")
		)
		(fp_line
			(start -0.67945 0.3048)
			(end -0.67945 -0.305054)
			(stroke
				(width 0.1)
				(type default)
			)
			(layer "F.Fab")
		)
		(fp_line
			(start -0.67945 -0.305054)
			(end -0.12065 -0.305054)
			(stroke
				(width 0.1)
				(type default)
			)
			(layer "F.Fab")
		)
		(pad "1" smd rect
			(at -0.40005 0)
			(size 0.4572 0.508)
			(layers "F.Cu" "F.Mask" "F.Paste")
			(net "P1V8_CPU0_RT_1D")
		)
		(pad "2" smd rect
			(at 0.40005 0)
			(size 0.4572 0.508)
			(layers "F.Cu" "F.Mask" "F.Paste")
			(net "P1V8_CPU0_RT0_1A_1D")
		)
	)
	(footprint ""
		(layer "F.Cu")
		(at 75.49515 -382.39446 180)
		(property "Reference" "C741"
			(at 0 0 180)
			(layer "F.SilkS")
			(hide yes)
			(effects
				(font
					(size 1.27 1.27)
				)
			)
		)
		(property "Value" ""
			(at 0 0 180)
			(layer "F.Fab")
			(effects
				(font
					(size 1.27 1.27)
				)
			)
		)
		(duplicate_pad_numbers_are_jumpers no)
		(fp_line
			(start 0.299974 0.150114)
			(end -0.299974 0.150114)
			(stroke
				(width 0.1)
				(type default)
			)
			(layer "F.Fab")
		)
		(fp_line
			(start 0.299974 -0.150114)
			(end 0.299974 0.150114)
			(stroke
				(width 0.1)
				(type default)
			)
			(layer "F.Fab")
		)
		(fp_line
			(start -0.299974 0.150114)
			(end -0.299974 -0.150114)
			(stroke
				(width 0.1)
				(type default)
			)
			(layer "F.Fab")
		)
		(fp_line
			(start -0.299974 -0.150114)
			(end 0.299974 -0.150114)
			(stroke
				(width 0.1)
				(type default)
			)
			(layer "F.Fab")
		)
		(pad "1" smd rect
			(at -0.2667 0 180)
			(size 0.3048 0.381)
			(layers "F.Cu" "F.Mask" "F.Paste")
			(net "P5E_CPU1_P1_TX_C_DP<0>")
		)
		(pad "2" smd rect
			(at 0.2667 0 180)
			(size 0.3048 0.381)
			(layers "F.Cu" "F.Mask" "F.Paste")
			(net "P5E_CPU1_P1_TX_DP<0>")
		)
	)
	(footprint ""
		(layer "F.Cu")
		(at 329.17384 -410.248608 90)
		(property "Reference" "C7003"
			(at 0 0 90)
			(layer "F.SilkS")
			(hide yes)
			(effects
				(font
					(size 1.27 1.27)
				)
			)
		)
		(property "Value" ""
			(at 0 0 90)
			(layer "F.Fab")
			(effects
				(font
					(size 1.27 1.27)
				)
			)
		)
		(duplicate_pad_numbers_are_jumpers no)
		(fp_line
			(start 1.524 -0.762)
			(end 1.524 0.762)
			(stroke
				(width 0.1524)
				(type default)
			)
			(layer "F.SilkS")
		)
		(fp_line
			(start -1.524 -0.762)
			(end 1.524 -0.762)
			(stroke
				(width 0.1524)
				(type default)
			)
			(layer "F.SilkS")
		)
		(fp_line
			(start 1.524 0.762)
			(end -1.524 0.762)
			(stroke
				(width 0.1524)
				(type default)
			)
			(layer "F.SilkS")
		)
		(fp_line
			(start -1.524 0.762)
			(end -1.524 -0.762)
			(stroke
				(width 0.1524)
				(type default)
			)
			(layer "F.SilkS")
		)
		(fp_line
			(start 1.1049 -0.724916)
			(end -1.1049 -0.724916)
			(stroke
				(width 0.1)
				(type default)
			)
			(layer "F.Fab")
		)
		(fp_line
			(start -1.1049 -0.724916)
			(end -1.1049 0.724916)
			(stroke
				(width 0.1)
				(type default)
			)
			(layer "F.Fab")
		)
		(fp_line
			(start 1.1049 0.724916)
			(end 1.1049 -0.724916)
			(stroke
				(width 0.1)
				(type default)
			)
			(layer "F.Fab")
		)
		(fp_line
			(start -1.1049 0.724916)
			(end 1.1049 0.724916)
			(stroke
				(width 0.1)
				(type default)
			)
			(layer "F.Fab")
		)
		(pad "1" smd rect
			(at -0.889 0 270)
			(size 1.016 1.27)
			(layers "F.Cu" "F.Mask" "F.Paste")
			(net "P0V9_CPU0_RT_2D")
		)
		(pad "2" smd rect
			(at 0.889 0 270)
			(size 1.016 1.27)
			(layers "F.Cu" "F.Mask" "F.Paste")
			(net "GND")
		)
	)
	(footprint ""
		(layer "F.Cu")
		(at 392.797538 -398.34058)
		(property "Reference" "R1414"
			(at 0 0 0)
			(layer "F.SilkS")
			(hide yes)
			(effects
				(font
					(size 1.27 1.27)
				)
			)
		)
		(property "Value" ""
			(at 0 0 0)
			(layer "F.Fab")
			(effects
				(font
					(size 1.27 1.27)
				)
			)
		)
		(duplicate_pad_numbers_are_jumpers no)
		(fp_line
			(start -0.32512 -0.175006)
			(end 0.32512 -0.175006)
			(stroke
				(width 0.1)
				(type default)
			)
			(layer "F.Fab")
		)
		(fp_line
			(start -0.32512 0.175006)
			(end -0.32512 -0.175006)
			(stroke
				(width 0.1)
				(type default)
			)
			(layer "F.Fab")
		)
		(fp_line
			(start 0.32512 -0.175006)
			(end 0.32512 0.175006)
			(stroke
				(width 0.1)
				(type default)
			)
			(layer "F.Fab")
		)
		(fp_line
			(start 0.32512 0.175006)
			(end -0.32512 0.175006)
			(stroke
				(width 0.1)
				(type default)
			)
			(layer "F.Fab")
		)
		(pad "1" smd rect
			(at -0.2667 0)
			(size 0.3048 0.381)
			(layers "F.Cu" "F.Mask" "F.Paste")
			(net "RXDET_BYP_RT_CPU0_P3")
		)
		(pad "2" smd rect
			(at 0.2667 0 180)
			(size 0.3048 0.381)
			(layers "F.Cu" "F.Mask" "F.Paste")
			(net "GND")
		)
	)
	(footprint ""
		(layer "F.Cu")
		(at 45.186854 -346.721176)
		(property "Reference" "PU40"
			(at -3.022854 -7.709154 0)
			(unlocked yes)
			(layer "F.SilkS")
			(effects
				(font
					(size 0.7874 0.5842)
					(thickness 0.1524)
				)
				(justify left)
			)
		)
		(property "Value" ""
			(at 0 0 0)
			(layer "F.Fab")
			(effects
				(font
					(size 1.27 1.27)
				)
			)
		)
		(duplicate_pad_numbers_are_jumpers no)
		(fp_line
			(start -2.500122 -2.999994)
			(end -2.24409 -2.999994)
			(stroke
				(width 0.1524)
				(type default)
			)
			(layer "F.SilkS")
		)
		(fp_line
			(start -2.500122 -2.529078)
			(end -2.500122 -2.999994)
			(stroke
				(width 0.1524)
				(type default)
			)
			(layer "F.SilkS")
		)
		(fp_line
			(start -2.500122 0.6604)
			(end -2.500122 0.229108)
			(stroke
				(width 0.1524)
				(type default)
			)
			(layer "F.SilkS")
		)
		(fp_line
			(start -2.500122 2.999994)
			(end -2.500122 2.339594)
			(stroke
				(width 0.1524)
				(type default)
			)
			(layer "F.SilkS")
		)
		(fp_line
			(start -2.2987 2.999994)
			(end -2.500122 2.999994)
			(stroke
				(width 0.1524)
				(type default)
			)
			(layer "F.SilkS")
		)
		(fp_line
			(start 2.31394 -2.999994)
			(end 2.500122 -2.999994)
			(stroke
				(width 0.1524)
				(type default)
			)
			(layer "F.SilkS")
		)
		(fp_line
			(start 2.500122 -2.999994)
			(end 2.500122 -2.44348)
			(stroke
				(width 0.1524)
				(type default)
			)
			(layer "F.SilkS")
		)
		(fp_line
			(start 2.500122 2.339594)
			(end 2.500122 2.999994)
			(stroke
				(width 0.1524)
				(type default)
			)
			(layer "F.SilkS")
		)
		(fp_line
			(start 2.500122 2.999994)
			(end 2.2987 2.999994)
			(stroke
				(width 0.1524)
				(type default)
			)
			(layer "F.SilkS")
		)
		(fp_poly
			(pts
				(xy -2.70129 -2.450084) (xy -3.374898 -2.674366) (xy -2.925826 -3.123438)
			)
			(stroke
				(width 0)
				(type default)
			)
			(fill yes)
			(layer "F.SilkS")
		)
		(fp_line
			(start -2.500122 -2.999994)
			(end 2.500122 -2.999994)
			(stroke
				(width 0.1)
				(type default)
			)
			(layer "F.Fab")
		)
		(fp_line
			(start -2.500122 2.999994)
			(end -2.500122 -2.999994)
			(stroke
				(width 0.1)
				(type default)
			)
			(layer "F.Fab")
		)
		(fp_line
			(start 2.500122 -2.999994)
			(end 2.500122 2.999994)
			(stroke
				(width 0.1)
				(type default)
			)
			(layer "F.Fab")
		)
		(fp_line
			(start 2.500122 2.999994)
			(end -2.500122 2.999994)
			(stroke
				(width 0.1)
				(type default)
			)
			(layer "F.Fab")
		)
		(fp_poly
			(pts
				(xy -4.218432 -2.783078) (xy -4.218432 -1.767078) (xy -3.202432 -2.275078)
			)
			(stroke
				(width 0)
				(type default)
			)
			(fill yes)
			(layer "F.Fab")
		)
		(pad "1" smd rect
			(at -2.400046 -2.275078 90)
			(size 0.2286 0.6096)
			(layers "F.Cu" "F.Mask" "F.Paste")
			(net "PVDDIO_P1_VOS2")
		)
		(pad "2" smd rect
			(at -2.400046 -1.82499 90)
			(size 0.2286 0.6096)
			(layers "F.Cu" "F.Mask" "F.Paste")
			(net "GND")
		)
		(pad "3" smd rect
			(at -2.400046 -1.374902 90)
			(size 0.2286 0.6096)
			(layers "F.Cu" "F.Mask" "F.Paste")
			(net "PVDDIO_P1_VCC2")
		)
		(pad "4" smd rect
			(at -2.400046 -0.925068 90)
			(size 0.2286 0.6096)
			(layers "F.Cu" "F.Mask" "F.Paste")
			(net "PVDDCR_CPU1_P1_PVCC")
		)
		(pad "5" smd rect
			(at -2.400046 -0.47498 90)
			(size 0.2286 0.6096)
			(layers "F.Cu" "F.Mask" "F.Paste")
			(net "GND")
		)
		(pad "6" smd rect
			(at -2.400046 -0.024892 90)
			(size 0.2286 0.6096)
			(layers "F.Cu" "F.Mask" "F.Paste")
			(net "NC_PVDDIO_P1_GL1_2")
		)
		(pad "7_9-20_24" smd circle
			(at 0 1.150112 90)
			(size 0 0)
			(layers "F.Cu" "F.Mask" "F.Paste")
			(net "GND")
		)
		(pad "10_19" smd rect
			(at 0 2.899918 90)
			(size 0.6096 4.318)
			(layers "F.Cu" "F.Mask" "F.Paste")
			(net "SW_PVDDIO_P1_SW2")
		)
		(pad "25_29" smd rect
			(at 1.549908 -1.279906 270)
			(size 2.0574 2.3114)
			(layers "F.Cu" "F.Mask" "F.Paste")
			(net "SW_P12V_AUX_PVDDIO_P1_FLT")
		)
		(pad "30" smd rect
			(at 2.05994 -2.899918)
			(size 0.2286 0.6096)
			(layers "F.Cu" "F.Mask" "F.Paste")
			(net "SW_P12V_AUX_PVDDIO_P1_FLT")
		)
		(pad "31" smd rect
			(at 1.610106 -2.899918)
			(size 0.2286 0.6096)
			(layers "F.Cu" "F.Mask" "F.Paste")
			(net "NC_PVDDIO_P1_DNC2")
		)
		(pad "32" smd rect
			(at 1.160018 -2.899918)
			(size 0.2286 0.6096)
			(layers "F.Cu" "F.Mask" "F.Paste")
			(net "SW_PVDDIO_P1_BOOTR2")
		)
		(pad "33" smd rect
			(at 0.70993 -2.899918)
			(size 0.2286 0.6096)
			(layers "F.Cu" "F.Mask" "F.Paste")
			(net "SW_PVDDIO_P1_BOOT2")
		)
		(pad "34" smd rect
			(at 0.260096 -2.899918)
			(size 0.2286 0.6096)
			(layers "F.Cu" "F.Mask" "F.Paste")
			(net "PVDDIO_P1_PWM2")
		)
		(pad "35" smd rect
			(at -0.189992 -2.899918)
			(size 0.2286 0.6096)
			(layers "F.Cu" "F.Mask" "F.Paste")
			(net "PVDDIO_P1_VCC2")
		)
		(pad "36" smd rect
			(at -0.64008 -2.899918)
			(size 0.2286 0.6096)
			(layers "F.Cu" "F.Mask" "F.Paste")
			(net "PVDDIO_P1_TEMP1")
		)
		(pad "37" smd rect
			(at -1.089914 -2.899918)
			(size 0.2286 0.6096)
			(layers "F.Cu" "F.Mask" "F.Paste")
			(net "PVDDIO_P1_LSET2")
		)
		(pad "38" smd rect
			(at -1.540002 -2.899918)
			(size 0.2286 0.6096)
			(layers "F.Cu" "F.Mask" "F.Paste")
			(net "PVDDIO_P1_IMON2")
		)
		(pad "39" smd rect
			(at -1.99009 -2.899918)
			(size 0.2286 0.6096)
			(layers "F.Cu" "F.Mask" "F.Paste")
			(net "PVDDCR_CPU1_P1_VCCS")
		)
		(pad "40" smd rect
			(at -0.87503 -1.27508)
			(size 1.7526 1.9558)
			(layers "F.Cu" "F.Mask" "F.Paste")
			(net "GND")
		)
		(pad "41" smd rect
			(at -1.525016 0.249936 270)
			(size 0.3048 0.4572)
			(layers "F.Cu" "F.Mask" "F.Paste")
			(net "NC_PVDDIO_P1_GL2_2")
		)
		(zone
			(layer "F.Cu")
			(hatch none 0.5)
			(connect_pads
				(clearance 0)
			)
			(min_thickness 0.25)
			(keepout
				(tracks not_allowed)
				(vias allowed)
				(pads allowed)
				(copperpour not_allowed)
				(footprints allowed)
			)
			(placement
				(enabled no)
				(sheetname "")
			)
			(fill
				(thermal_gap 0.5)
				(thermal_bridge_width 0.5)
				(island_removal_mode 0)
			)
			(polygon
				(pts
					(xy 42.686732 -344.1446) (xy 42.686732 -344.470482) (xy 47.686976 -344.470482) (xy 47.686976 -344.148664)
					(xy 47.396654 -344.148664) (xy 47.396654 -344.176858) (xy 42.977054 -344.176858) (xy 42.977054 -344.1446)
				)
			)
		)
		(zone
			(layer "F.Cu")
			(hatch none 0.5)
			(connect_pads
				(clearance 0)
			)
			(min_thickness 0.25)
			(keepout
				(tracks not_allowed)
				(vias allowed)
				(pads allowed)
				(copperpour not_allowed)
				(footprints allowed)
			)
			(placement
				(enabled no)
				(sheetname "")
			)
			(fill
				(thermal_gap 0.5)
				(thermal_bridge_width 0.5)
				(island_removal_mode 0)
			)
			(polygon
				(pts
					(xy 45.2374 -346.967556) (xy 45.238924 -346.967556) (xy 45.238924 -349.024956) (xy 43.384724 -349.024956)
					(xy 43.384724 -348.78391) (xy 43.142408 -348.78391) (xy 43.142408 -349.265494) (xy 46.98238 -349.265494)
					(xy 46.98238 -349.080582) (xy 45.530262 -349.080582) (xy 45.530262 -346.921582) (xy 47.686976 -346.921582)
					(xy 47.686976 -346.6719) (xy 45.456856 -346.6719) (xy 45.2374 -346.891356)
				)
			)
		)
	)
)
